(kicad_pcb
	(version 20260206)
	(generator "pcbnew")
	(generator_version "10.0")
	(general
		(thickness 1.6)
		(legacy_teardrops no)
	)
	(paper "A4")
	(title_block
		(title "03242023_DA0F0TMBIJ0_F0T_Motherboard_J_brd_V01_OCP.brd")
		(comment 1 "Grand Teton / footprint 3833 of 6105 (J14), pads 1-112 of 291")
	)
	(layers
		(0 "F.Cu" signal "TOP")
		(4 "In1.Cu" signal "GND")
		(6 "In2.Cu" signal "IN1")
		(8 "In3.Cu" signal "GND1")
		(10 "In4.Cu" signal "IN2")
		(12 "In5.Cu" signal "GND2")
		(14 "In6.Cu" signal "IN3")
		(16 "In7.Cu" signal "GND3")
		(18 "In8.Cu" signal "VCC")
		(20 "In9.Cu" signal "VCC1")
		(22 "In10.Cu" signal "GND4")
		(24 "In11.Cu" signal "IN4")
		(26 "In12.Cu" signal "GND5")
		(28 "In13.Cu" signal "IN5")
		(30 "In14.Cu" signal "GND6")
		(32 "In15.Cu" signal "IN6")
		(34 "In16.Cu" signal "GND7")
		(2 "B.Cu" signal "BOTTOM")
		(9 "F.Adhes" user "F.Adhesive")
		(11 "B.Adhes" user "B.Adhesive")
		(13 "F.Paste" user "Package Geometry/Pastemask Top")
		(15 "B.Paste" user "Package Geometry/Pastemask Bottom")
		(5 "F.SilkS" user "Ref Des/Silkscreen Top")
		(7 "B.SilkS" user "Ref Des/Silkscreen Bottom")
		(1 "F.Mask" user "Board Geometry/Soldermask Top")
		(3 "B.Mask" user "Board Geometry/Soldermask Bottom")
		(17 "Dwgs.User" user "User.Drawings")
		(19 "Cmts.User" user "User.Comments")
		(21 "Eco1.User" user "User.Eco1")
		(23 "Eco2.User" user "User.Eco2")
		(25 "Edge.Cuts" user "Board Geometry/Outline")
		(27 "Margin" user)
		(31 "F.CrtYd" user "Package Geometry/Place Bound Top")
		(29 "B.CrtYd" user "Package Geometry/Place Bound Bottom")
		(35 "F.Fab" user "Ref Des/Assembly Top")
		(33 "B.Fab" user "Ref Des/Assembly Bottom")
	)
	(footprint ""
		(layer "F.Cu")
		(at 438.978548 -258.091686)
		(property "Reference" "J14"
			(at -3.683 -81.702148 0)
			(unlocked yes)
			(layer "F.SilkS")
			(effects
				(font
					(size 0.7874 0.5842)
					(thickness 0.1524)
				)
				(justify left)
			)
		)
		(property "Value" ""
			(at 0 0 0)
			(layer "F.Fab")
			(effects
				(font
					(size 1.27 1.27)
				)
			)
		)
		(duplicate_pad_numbers_are_jumpers no)
		(pad "1" smd rect
			(at -2.050034 -63.324994 270)
			(size 0.519938 1.4986)
			(layers "F.Cu" "F.Mask" "F.Paste")
			(net "P12V_S3_AUX_CPU0_NVDIMM")
		)
		(pad "2" smd rect
			(at -2.050034 -62.47511 270)
			(size 0.519938 1.4986)
			(layers "F.Cu" "F.Mask" "F.Paste")
			(net "TP_CHG_CPU0_DIMM2_FRU_0")
		)
		(pad "3" smd rect
			(at -2.050034 -61.624972 270)
			(size 0.519938 1.4986)
			(layers "F.Cu" "F.Mask" "F.Paste")
			(net "P3V3_AUX")
		)
		(pad "4" smd rect
			(at -2.050034 -60.775088 270)
			(size 0.519938 1.4986)
			(layers "F.Cu" "F.Mask" "F.Paste")
			(net "I3C_SPD_DDREFGH_CPU0_LVC1_SCL_5")
		)
		(pad "5" smd rect
			(at -2.050034 -59.92495 270)
			(size 0.519938 1.4986)
			(layers "F.Cu" "F.Mask" "F.Paste")
			(net "I3C_SPD_DDREFGH_CPU0_LVC1_SDA")
		)
		(pad "6" smd rect
			(at -2.050034 -59.075066 270)
			(size 0.519938 1.4986)
			(layers "F.Cu" "F.Mask" "F.Paste")
			(net "GND")
		)
		(pad "7" smd rect
			(at -2.050034 -58.224928 270)
			(size 0.519938 1.4986)
			(layers "F.Cu" "F.Mask" "F.Paste")
			(net "M_G_CPU0_SA_DQ<0>")
		)
		(pad "8" smd rect
			(at -2.050034 -57.375044 270)
			(size 0.519938 1.4986)
			(layers "F.Cu" "F.Mask" "F.Paste")
			(net "GND")
		)
		(pad "9" smd rect
			(at -2.050034 -56.524906 270)
			(size 0.519938 1.4986)
			(layers "F.Cu" "F.Mask" "F.Paste")
			(net "M_G_CPU0_SA_DQ<1>")
		)
		(pad "10" smd rect
			(at -2.050034 -55.675022 270)
			(size 0.519938 1.4986)
			(layers "F.Cu" "F.Mask" "F.Paste")
			(net "GND")
		)
		(pad "11" smd rect
			(at -2.050034 -54.824884 270)
			(size 0.519938 1.4986)
			(layers "F.Cu" "F.Mask" "F.Paste")
			(net "M_G_CPU0_SA_DQS_DP<0>")
		)
		(pad "12" smd rect
			(at -2.050034 -53.975 270)
			(size 0.519938 1.4986)
			(layers "F.Cu" "F.Mask" "F.Paste")
			(net "M_G_CPU0_SA_DQS_DN<0>")
		)
		(pad "13" smd rect
			(at -2.050034 -53.125116 270)
			(size 0.519938 1.4986)
			(layers "F.Cu" "F.Mask" "F.Paste")
			(net "GND")
		)
		(pad "14" smd rect
			(at -2.050034 -52.274978 270)
			(size 0.519938 1.4986)
			(layers "F.Cu" "F.Mask" "F.Paste")
			(net "M_G_CPU0_SA_DQ<4>")
		)
		(pad "15" smd rect
			(at -2.050034 -51.425094 270)
			(size 0.519938 1.4986)
			(layers "F.Cu" "F.Mask" "F.Paste")
			(net "GND")
		)
		(pad "16" smd rect
			(at -2.050034 -50.574956 270)
			(size 0.519938 1.4986)
			(layers "F.Cu" "F.Mask" "F.Paste")
			(net "M_G_CPU0_SA_DQ<5>")
		)
		(pad "17" smd rect
			(at -2.050034 -49.725072 270)
			(size 0.519938 1.4986)
			(layers "F.Cu" "F.Mask" "F.Paste")
			(net "GND")
		)
		(pad "18" smd rect
			(at -2.050034 -48.874934 270)
			(size 0.519938 1.4986)
			(layers "F.Cu" "F.Mask" "F.Paste")
			(net "M_G_CPU0_SA_DQ<8>")
		)
		(pad "19" smd rect
			(at -2.050034 -48.02505 270)
			(size 0.519938 1.4986)
			(layers "F.Cu" "F.Mask" "F.Paste")
			(net "GND")
		)
		(pad "20" smd rect
			(at -2.050034 -47.174912 270)
			(size 0.519938 1.4986)
			(layers "F.Cu" "F.Mask" "F.Paste")
			(net "M_G_CPU0_SA_DQ<9>")
		)
		(pad "21" smd rect
			(at -2.050034 -46.325028 270)
			(size 0.519938 1.4986)
			(layers "F.Cu" "F.Mask" "F.Paste")
			(net "GND")
		)
		(pad "22" smd rect
			(at -2.050034 -45.47489 270)
			(size 0.519938 1.4986)
			(layers "F.Cu" "F.Mask" "F.Paste")
			(net "M_G_CPU0_SA_DQS_DP<1>")
		)
		(pad "23" smd rect
			(at -2.050034 -44.625006 270)
			(size 0.519938 1.4986)
			(layers "F.Cu" "F.Mask" "F.Paste")
			(net "M_G_CPU0_SA_DQS_DN<1>")
		)
		(pad "24" smd rect
			(at -2.050034 -43.775122 270)
			(size 0.519938 1.4986)
			(layers "F.Cu" "F.Mask" "F.Paste")
			(net "GND")
		)
		(pad "25" smd rect
			(at -2.050034 -42.924984 270)
			(size 0.519938 1.4986)
			(layers "F.Cu" "F.Mask" "F.Paste")
			(net "M_G_CPU0_SA_DQ<12>")
		)
		(pad "26" smd rect
			(at -2.050034 -42.0751 270)
			(size 0.519938 1.4986)
			(layers "F.Cu" "F.Mask" "F.Paste")
			(net "GND")
		)
		(pad "27" smd rect
			(at -2.050034 -41.224962 270)
			(size 0.519938 1.4986)
			(layers "F.Cu" "F.Mask" "F.Paste")
			(net "M_G_CPU0_SA_DQ<13>")
		)
		(pad "28" smd rect
			(at -2.050034 -40.375078 270)
			(size 0.519938 1.4986)
			(layers "F.Cu" "F.Mask" "F.Paste")
			(net "GND")
		)
		(pad "29" smd rect
			(at -2.050034 -39.52494 270)
			(size 0.519938 1.4986)
			(layers "F.Cu" "F.Mask" "F.Paste")
			(net "M_G_CPU0_SA_DQ<16>")
		)
		(pad "30" smd rect
			(at -2.050034 -38.675056 270)
			(size 0.519938 1.4986)
			(layers "F.Cu" "F.Mask" "F.Paste")
			(net "GND")
		)
		(pad "31" smd rect
			(at -2.050034 -37.824918 270)
			(size 0.519938 1.4986)
			(layers "F.Cu" "F.Mask" "F.Paste")
			(net "M_G_CPU0_SA_DQ<17>")
		)
		(pad "32" smd rect
			(at -2.050034 -36.975034 270)
			(size 0.519938 1.4986)
			(layers "F.Cu" "F.Mask" "F.Paste")
			(net "GND")
		)
		(pad "33" smd rect
			(at -2.050034 -36.124896 270)
			(size 0.519938 1.4986)
			(layers "F.Cu" "F.Mask" "F.Paste")
			(net "M_G_CPU0_SA_DQS_DP<2>")
		)
		(pad "34" smd rect
			(at -2.050034 -35.275012 270)
			(size 0.519938 1.4986)
			(layers "F.Cu" "F.Mask" "F.Paste")
			(net "M_G_CPU0_SA_DQS_DN<2>")
		)
		(pad "35" smd rect
			(at -2.050034 -34.425128 270)
			(size 0.519938 1.4986)
			(layers "F.Cu" "F.Mask" "F.Paste")
			(net "GND")
		)
		(pad "36" smd rect
			(at -2.050034 -33.57499 270)
			(size 0.519938 1.4986)
			(layers "F.Cu" "F.Mask" "F.Paste")
			(net "M_G_CPU0_SA_DQ<20>")
		)
		(pad "37" smd rect
			(at -2.050034 -32.725106 270)
			(size 0.519938 1.4986)
			(layers "F.Cu" "F.Mask" "F.Paste")
			(net "GND")
		)
		(pad "38" smd rect
			(at -2.050034 -31.874968 270)
			(size 0.519938 1.4986)
			(layers "F.Cu" "F.Mask" "F.Paste")
			(net "M_G_CPU0_SA_DQ<21>")
		)
		(pad "39" smd rect
			(at -2.050034 -31.025084 270)
			(size 0.519938 1.4986)
			(layers "F.Cu" "F.Mask" "F.Paste")
			(net "GND")
		)
		(pad "40" smd rect
			(at -2.050034 -30.174946 270)
			(size 0.519938 1.4986)
			(layers "F.Cu" "F.Mask" "F.Paste")
			(net "M_G_CPU0_SA_DQ<24>")
		)
		(pad "41" smd rect
			(at -2.050034 -29.325062 270)
			(size 0.519938 1.4986)
			(layers "F.Cu" "F.Mask" "F.Paste")
			(net "GND")
		)
		(pad "42" smd rect
			(at -2.050034 -28.474924 270)
			(size 0.519938 1.4986)
			(layers "F.Cu" "F.Mask" "F.Paste")
			(net "M_G_CPU0_SA_DQ<25>")
		)
		(pad "43" smd rect
			(at -2.050034 -27.62504 270)
			(size 0.519938 1.4986)
			(layers "F.Cu" "F.Mask" "F.Paste")
			(net "GND")
		)
		(pad "44" smd rect
			(at -2.050034 -26.774902 270)
			(size 0.519938 1.4986)
			(layers "F.Cu" "F.Mask" "F.Paste")
			(net "M_G_CPU0_SA_DQS_DP<3>")
		)
		(pad "45" smd rect
			(at -2.050034 -25.925018 270)
			(size 0.519938 1.4986)
			(layers "F.Cu" "F.Mask" "F.Paste")
			(net "M_G_CPU0_SA_DQS_DN<3>")
		)
		(pad "46" smd rect
			(at -2.050034 -25.07488 270)
			(size 0.519938 1.4986)
			(layers "F.Cu" "F.Mask" "F.Paste")
			(net "GND")
		)
		(pad "47" smd rect
			(at -2.050034 -24.224996 270)
			(size 0.519938 1.4986)
			(layers "F.Cu" "F.Mask" "F.Paste")
			(net "M_G_CPU0_SA_DQ<28>")
		)
		(pad "48" smd rect
			(at -2.050034 -23.375112 270)
			(size 0.519938 1.4986)
			(layers "F.Cu" "F.Mask" "F.Paste")
			(net "GND")
		)
		(pad "49" smd rect
			(at -2.050034 -22.524974 270)
			(size 0.519938 1.4986)
			(layers "F.Cu" "F.Mask" "F.Paste")
			(net "M_G_CPU0_SA_DQ<29>")
		)
		(pad "50" smd rect
			(at -2.050034 -21.67509 270)
			(size 0.519938 1.4986)
			(layers "F.Cu" "F.Mask" "F.Paste")
			(net "GND")
		)
		(pad "51" smd rect
			(at -2.050034 -20.824952 270)
			(size 0.519938 1.4986)
			(layers "F.Cu" "F.Mask" "F.Paste")
			(net "M_G_CPU0_SA_CB<0>")
		)
		(pad "52" smd rect
			(at -2.050034 -19.975068 270)
			(size 0.519938 1.4986)
			(layers "F.Cu" "F.Mask" "F.Paste")
			(net "GND")
		)
		(pad "53" smd rect
			(at -2.050034 -19.12493 270)
			(size 0.519938 1.4986)
			(layers "F.Cu" "F.Mask" "F.Paste")
			(net "M_G_CPU0_SA_CB<1>")
		)
		(pad "54" smd rect
			(at -2.050034 -18.275046 270)
			(size 0.519938 1.4986)
			(layers "F.Cu" "F.Mask" "F.Paste")
			(net "GND")
		)
		(pad "55" smd rect
			(at -2.050034 -17.424908 270)
			(size 0.519938 1.4986)
			(layers "F.Cu" "F.Mask" "F.Paste")
			(net "M_G_CPU0_SA_DQS_DP<4>")
		)
		(pad "56" smd rect
			(at -2.050034 -16.575024 270)
			(size 0.519938 1.4986)
			(layers "F.Cu" "F.Mask" "F.Paste")
			(net "M_G_CPU0_SA_DQS_DN<4>")
		)
		(pad "57" smd rect
			(at -2.050034 -15.724886 270)
			(size 0.519938 1.4986)
			(layers "F.Cu" "F.Mask" "F.Paste")
			(net "GND")
		)
		(pad "58" smd rect
			(at -2.050034 -14.875002 270)
			(size 0.519938 1.4986)
			(layers "F.Cu" "F.Mask" "F.Paste")
			(net "M_G_CPU0_SA_CB<4>")
		)
		(pad "59" smd rect
			(at -2.050034 -14.025118 270)
			(size 0.519938 1.4986)
			(layers "F.Cu" "F.Mask" "F.Paste")
			(net "GND")
		)
		(pad "60" smd rect
			(at -2.050034 -13.17498 270)
			(size 0.519938 1.4986)
			(layers "F.Cu" "F.Mask" "F.Paste")
			(net "M_G_CPU0_SA_CB<5>")
		)
		(pad "61" smd rect
			(at -2.050034 -12.325096 270)
			(size 0.519938 1.4986)
			(layers "F.Cu" "F.Mask" "F.Paste")
			(net "GND")
		)
		(pad "62" smd rect
			(at -2.050034 -11.474958 270)
			(size 0.519938 1.4986)
			(layers "F.Cu" "F.Mask" "F.Paste")
			(net "M_G_CPU0_ALERT_N")
		)
		(pad "63" smd rect
			(at -2.050034 -10.625074 270)
			(size 0.519938 1.4986)
			(layers "F.Cu" "F.Mask" "F.Paste")
			(net "GND")
		)
		(pad "64" smd rect
			(at -2.050034 -9.774936 270)
			(size 0.519938 1.4986)
			(layers "F.Cu" "F.Mask" "F.Paste")
			(net "M_G_CPU0_SA_CS_N<2>")
		)
		(pad "65" smd rect
			(at -2.050034 -8.925052 270)
			(size 0.519938 1.4986)
			(layers "F.Cu" "F.Mask" "F.Paste")
			(net "GND")
		)
		(pad "66" smd rect
			(at -2.050034 -8.074914 270)
			(size 0.519938 1.4986)
			(layers "F.Cu" "F.Mask" "F.Paste")
			(net "M_G_CPU0_SA_CA<0>")
		)
		(pad "67" smd rect
			(at -2.050034 -7.22503 270)
			(size 0.519938 1.4986)
			(layers "F.Cu" "F.Mask" "F.Paste")
			(net "GND")
		)
		(pad "68" smd rect
			(at -2.050034 -6.374892 270)
			(size 0.519938 1.4986)
			(layers "F.Cu" "F.Mask" "F.Paste")
			(net "M_G_CPU0_SA_CA<2>")
		)
		(pad "69" smd rect
			(at -2.050034 -5.525008 270)
			(size 0.519938 1.4986)
			(layers "F.Cu" "F.Mask" "F.Paste")
			(net "GND")
		)
		(pad "70" smd rect
			(at -2.050034 -4.675124 270)
			(size 0.519938 1.4986)
			(layers "F.Cu" "F.Mask" "F.Paste")
			(net "M_G_CPU0_SA_CA<4>")
		)
		(pad "71" smd rect
			(at -2.050034 -3.824986 270)
			(size 0.519938 1.4986)
			(layers "F.Cu" "F.Mask" "F.Paste")
			(net "GND")
		)
		(pad "72" smd rect
			(at -2.050034 -2.975102 270)
			(size 0.519938 1.4986)
			(layers "F.Cu" "F.Mask" "F.Paste")
			(net "M_G_CPU0_SA_CA<6>")
		)
		(pad "73" smd rect
			(at -2.050034 -2.124964 270)
			(size 0.519938 1.4986)
			(layers "F.Cu" "F.Mask" "F.Paste")
			(net "GND")
		)
		(pad "74" smd rect
			(at -2.050034 -1.27508 270)
			(size 0.519938 1.4986)
			(layers "F.Cu" "F.Mask" "F.Paste")
			(net "M_G_CPU0_SA_PAR")
		)
		(pad "75" smd rect
			(at -2.050034 -0.424942 270)
			(size 0.519938 1.4986)
			(layers "F.Cu" "F.Mask" "F.Paste")
			(net "GND")
		)
		(pad "76" smd rect
			(at -2.050034 5.525008 270)
			(size 0.519938 1.4986)
			(layers "F.Cu" "F.Mask" "F.Paste")
			(net "M_G_CPU0_SB_CA<0>")
		)
		(pad "77" smd rect
			(at -2.050034 6.374892 270)
			(size 0.519938 1.4986)
			(layers "F.Cu" "F.Mask" "F.Paste")
			(net "GND")
		)
		(pad "78" smd rect
			(at -2.050034 7.22503 270)
			(size 0.519938 1.4986)
			(layers "F.Cu" "F.Mask" "F.Paste")
			(net "M_G_CPU0_SB_CA<2>")
		)
		(pad "79" smd rect
			(at -2.050034 8.074914 270)
			(size 0.519938 1.4986)
			(layers "F.Cu" "F.Mask" "F.Paste")
			(net "GND")
		)
		(pad "80" smd rect
			(at -2.050034 8.925052 270)
			(size 0.519938 1.4986)
			(layers "F.Cu" "F.Mask" "F.Paste")
			(net "M_G_CPU0_SB_CA<4>")
		)
		(pad "81" smd rect
			(at -2.050034 9.774936 270)
			(size 0.519938 1.4986)
			(layers "F.Cu" "F.Mask" "F.Paste")
			(net "GND")
		)
		(pad "82" smd rect
			(at -2.050034 10.625074 270)
			(size 0.519938 1.4986)
			(layers "F.Cu" "F.Mask" "F.Paste")
			(net "M_G_CPU0_SB_CA<6>")
		)
		(pad "83" smd rect
			(at -2.050034 11.474958 270)
			(size 0.519938 1.4986)
			(layers "F.Cu" "F.Mask" "F.Paste")
			(net "GND")
		)
		(pad "84" smd rect
			(at -2.050034 12.325096 270)
			(size 0.519938 1.4986)
			(layers "F.Cu" "F.Mask" "F.Paste")
			(net "M_G_CPU0_SB_CS_N<2>")
		)
		(pad "85" smd rect
			(at -2.050034 13.17498 270)
			(size 0.519938 1.4986)
			(layers "F.Cu" "F.Mask" "F.Paste")
			(net "GND")
		)
		(pad "86" smd rect
			(at -2.050034 14.025118 270)
			(size 0.519938 1.4986)
			(layers "F.Cu" "F.Mask" "F.Paste")
			(net "M_G_CPU0_SA_RSP<1>")
		)
		(pad "87" smd rect
			(at -2.050034 14.875002 270)
			(size 0.519938 1.4986)
			(layers "F.Cu" "F.Mask" "F.Paste")
			(net "M_G_CPU0_SB_RSP<1>")
		)
		(pad "88" smd rect
			(at -2.050034 15.724886 270)
			(size 0.519938 1.4986)
			(layers "F.Cu" "F.Mask" "F.Paste")
			(net "GND")
		)
		(pad "89" smd rect
			(at -2.050034 16.575024 270)
			(size 0.519938 1.4986)
			(layers "F.Cu" "F.Mask" "F.Paste")
			(net "M_G_CPU0_SB_CB<4>")
		)
		(pad "90" smd rect
			(at -2.050034 17.424908 270)
			(size 0.519938 1.4986)
			(layers "F.Cu" "F.Mask" "F.Paste")
			(net "GND")
		)
		(pad "91" smd rect
			(at -2.050034 18.275046 270)
			(size 0.519938 1.4986)
			(layers "F.Cu" "F.Mask" "F.Paste")
			(net "M_G_CPU0_SB_CB<5>")
		)
		(pad "92" smd rect
			(at -2.050034 19.12493 270)
			(size 0.519938 1.4986)
			(layers "F.Cu" "F.Mask" "F.Paste")
			(net "GND")
		)
		(pad "93" smd rect
			(at -2.050034 19.975068 270)
			(size 0.519938 1.4986)
			(layers "F.Cu" "F.Mask" "F.Paste")
			(net "M_G_CPU0_SB_DQS_DP<9>")
		)
		(pad "94" smd rect
			(at -2.050034 20.824952 270)
			(size 0.519938 1.4986)
			(layers "F.Cu" "F.Mask" "F.Paste")
			(net "M_G_CPU0_SB_DQS_DN<9>")
		)
		(pad "95" smd rect
			(at -2.050034 21.67509 270)
			(size 0.519938 1.4986)
			(layers "F.Cu" "F.Mask" "F.Paste")
			(net "GND")
		)
		(pad "96" smd rect
			(at -2.050034 22.524974 270)
			(size 0.519938 1.4986)
			(layers "F.Cu" "F.Mask" "F.Paste")
			(net "M_G_CPU0_SB_CB<0>")
		)
		(pad "97" smd rect
			(at -2.050034 23.375112 270)
			(size 0.519938 1.4986)
			(layers "F.Cu" "F.Mask" "F.Paste")
			(net "GND")
		)
		(pad "98" smd rect
			(at -2.050034 24.224996 270)
			(size 0.519938 1.4986)
			(layers "F.Cu" "F.Mask" "F.Paste")
			(net "M_G_CPU0_SB_CB<1>")
		)
		(pad "99" smd rect
			(at -2.050034 25.07488 270)
			(size 0.519938 1.4986)
			(layers "F.Cu" "F.Mask" "F.Paste")
			(net "GND")
		)
		(pad "100" smd rect
			(at -2.050034 25.925018 270)
			(size 0.519938 1.4986)
			(layers "F.Cu" "F.Mask" "F.Paste")
			(net "M_G_CPU0_SB_DQ<0>")
		)
		(pad "101" smd rect
			(at -2.050034 26.774902 270)
			(size 0.519938 1.4986)
			(layers "F.Cu" "F.Mask" "F.Paste")
			(net "GND")
		)
		(pad "102" smd rect
			(at -2.050034 27.62504 270)
			(size 0.519938 1.4986)
			(layers "F.Cu" "F.Mask" "F.Paste")
			(net "M_G_CPU0_SB_DQ<1>")
		)
		(pad "103" smd rect
			(at -2.050034 28.474924 270)
			(size 0.519938 1.4986)
			(layers "F.Cu" "F.Mask" "F.Paste")
			(net "GND")
		)
		(pad "104" smd rect
			(at -2.050034 29.325062 270)
			(size 0.519938 1.4986)
			(layers "F.Cu" "F.Mask" "F.Paste")
			(net "M_G_CPU0_SB_DQS_DP<0>")
		)
		(pad "105" smd rect
			(at -2.050034 30.174946 270)
			(size 0.519938 1.4986)
			(layers "F.Cu" "F.Mask" "F.Paste")
			(net "M_G_CPU0_SB_DQS_DN<0>")
		)
		(pad "106" smd rect
			(at -2.050034 31.025084 270)
			(size 0.519938 1.4986)
			(layers "F.Cu" "F.Mask" "F.Paste")
			(net "GND")
		)
		(pad "107" smd rect
			(at -2.050034 31.874968 270)
			(size 0.519938 1.4986)
			(layers "F.Cu" "F.Mask" "F.Paste")
			(net "M_G_CPU0_SB_DQ<4>")
		)
		(pad "108" smd rect
			(at -2.050034 32.725106 270)
			(size 0.519938 1.4986)
			(layers "F.Cu" "F.Mask" "F.Paste")
			(net "GND")
		)
		(pad "109" smd rect
			(at -2.050034 33.57499 270)
			(size 0.519938 1.4986)
			(layers "F.Cu" "F.Mask" "F.Paste")
			(net "M_G_CPU0_SB_DQ<5>")
		)
		(pad "110" smd rect
			(at -2.050034 34.425128 270)
			(size 0.519938 1.4986)
			(layers "F.Cu" "F.Mask" "F.Paste")
			(net "GND")
		)
		(pad "111" smd rect
			(at -2.050034 35.275012 270)
			(size 0.519938 1.4986)
			(layers "F.Cu" "F.Mask" "F.Paste")
			(net "M_G_CPU0_SB_DQ<8>")
		)
		(pad "112" smd rect
			(at -2.050034 36.124896 270)
			(size 0.519938 1.4986)
			(layers "F.Cu" "F.Mask" "F.Paste")
			(net "GND")
		)
	)
)
